(kicad_pcb
	(version 20260206)
	(generator "pcbnew")
	(generator_version "10.0")
	(general
		(thickness 1.21888)
		(legacy_teardrops no)
	)
	(paper "A4")
	(title_block
		(title "timecard-v9 — TimeCard-DC-V9_EXP.PcbDoc")
		(comment 1 "Time Appliance Project (Time Card) / footprints 187-191 of 402")
	)
	(layers
		(0 "F.Cu" signal "TOP")
		(4 "In1.Cu" signal "SGND")
		(6 "In2.Cu" signal "IN1")
		(8 "In3.Cu" signal "IN2")
		(10 "In4.Cu" signal "SGND1")
		(2 "B.Cu" signal "BOTTOM")
		(9 "F.Adhes" user "F.Adhesive")
		(11 "B.Adhes" user "B.Adhesive")
		(13 "F.Paste" user "Top Paste")
		(15 "B.Paste" user "Bottom Paste")
		(5 "F.SilkS" user "Top Overlay")
		(7 "B.SilkS" user "Bottom Overlay")
		(1 "F.Mask" user "Top Solder")
		(3 "B.Mask" user "Bottom Solder")
		(17 "Dwgs.User" user "User.Drawings")
		(19 "Cmts.User" user "User.Comments")
		(21 "Eco1.User" user "User.Eco1")
		(23 "Eco2.User" user "User.Eco2")
		(25 "Edge.Cuts" user)
		(27 "Margin" user)
		(31 "F.CrtYd" user "Top Courtyard")
		(29 "B.CrtYd" user "Bottom Courtyard")
		(35 "F.Fab" user "Top Component Center")
		(33 "B.Fab" user "Bottom Component Center")
	)
	(footprint "Vault:FP-RUT0012A-MFG"
		(layer "F.Cu")
		(at 154.8216 116.0162)
		(property "Reference" "U26"
			(at 2.3032 -2.273079 0)
			(unlocked yes)
			(layer "F.SilkS")
			(effects
				(font
					(size 0.762 0.762)
					(thickness 0.2032)
				)
			)
		)
		(property "Value" "TMUX1072RUTR"
			(at 7.401265 3.164071 0)
			(unlocked yes)
			(layer "F.SilkS")
			(hide yes)
			(effects
				(font
					(size 0.762 0.762)
					(thickness 0.2032)
				)
			)
		)
		(sheetname "08-DIPSwitches_I2C")
		(sheetfile "08-DIPSwitches_I2C.kicad_sch")
		(duplicate_pad_numbers_are_jumpers no)
		(fp_line
			(start -0.9 -1.525)
			(end 0.9 -1.525)
			(stroke
				(width 0.2)
				(type solid)
			)
			(layer "F.SilkS")
		)
		(fp_line
			(start -0.9 1.525)
			(end 0.9 1.525)
			(stroke
				(width 0.2)
				(type solid)
			)
			(layer "F.SilkS")
		)
		(fp_circle
			(center -1.575 -0.8)
			(end -1.575 -0.925)
			(stroke
				(width 0.25)
				(type solid)
			)
			(fill no)
			(layer "F.SilkS")
		)
		(fp_rect
			(start -0.85 -0.3)
			(end -0.35 -0.5)
			(stroke
				(width 0)
				(type default)
			)
			(fill yes)
			(layer "F.Paste")
		)
		(fp_rect
			(start -0.85 0.1)
			(end -0.35 -0.1)
			(stroke
				(width 0)
				(type default)
			)
			(fill yes)
			(layer "F.Paste")
		)
		(fp_rect
			(start -0.85 0.5)
			(end -0.35 0.3)
			(stroke
				(width 0)
				(type default)
			)
			(fill yes)
			(layer "F.Paste")
		)
		(fp_rect
			(start -0.85 0.9)
			(end -0.35 0.7)
			(stroke
				(width 0)
				(type default)
			)
			(fill yes)
			(layer "F.Paste")
		)
		(fp_rect
			(start -0.1 -0.5)
			(end 0.1 -1)
			(stroke
				(width 0)
				(type default)
			)
			(fill yes)
			(layer "F.Paste")
		)
		(fp_rect
			(start -0.1 1)
			(end 0.1 0.5)
			(stroke
				(width 0)
				(type default)
			)
			(fill yes)
			(layer "F.Paste")
		)
		(fp_rect
			(start 0.35 -0.7)
			(end 0.85 -0.9)
			(stroke
				(width 0)
				(type default)
			)
			(fill yes)
			(layer "F.Paste")
		)
		(fp_rect
			(start 0.35 -0.3)
			(end 0.85 -0.5)
			(stroke
				(width 0)
				(type default)
			)
			(fill yes)
			(layer "F.Paste")
		)
		(fp_rect
			(start 0.35 0.1)
			(end 0.85 -0.1)
			(stroke
				(width 0)
				(type default)
			)
			(fill yes)
			(layer "F.Paste")
		)
		(fp_rect
			(start 0.35 0.5)
			(end 0.85 0.3)
			(stroke
				(width 0)
				(type default)
			)
			(fill yes)
			(layer "F.Paste")
		)
		(fp_rect
			(start 0.35 0.9)
			(end 0.85 0.7)
			(stroke
				(width 0)
				(type default)
			)
			(fill yes)
			(layer "F.Paste")
		)
		(fp_poly
			(pts
				(xy -0.5 -1) (xy -0.35 -1) (xy -0.35 -0.7) (xy -0.85 -0.7) (xy -0.85 -0.9) (xy -0.5 -0.9)
			)
			(stroke
				(width 0)
				(type default)
			)
			(fill yes)
			(layer "F.Paste")
		)
		(fp_line
			(start -1.05 -1.2)
			(end 1.05 -1.2)
			(stroke
				(width 0.2)
				(type solid)
			)
			(layer "F.CrtYd")
		)
		(fp_line
			(start -1.05 1.2)
			(end -1.05 -1.2)
			(stroke
				(width 0.2)
				(type solid)
			)
			(layer "F.CrtYd")
		)
		(fp_line
			(start -1.05 1.2)
			(end 1.05 1.2)
			(stroke
				(width 0.2)
				(type solid)
			)
			(layer "F.CrtYd")
		)
		(fp_line
			(start 1.05 1.2)
			(end 1.05 -1.2)
			(stroke
				(width 0.2)
				(type solid)
			)
			(layer "F.CrtYd")
		)
		(fp_line
			(start -1.05 -1.2)
			(end 1.05 -1.2)
			(stroke
				(width 0.2)
				(type solid)
			)
			(layer "F.Fab")
		)
		(fp_line
			(start -1.05 1.2)
			(end -1.05 -1.2)
			(stroke
				(width 0.2)
				(type solid)
			)
			(layer "F.Fab")
		)
		(fp_line
			(start -1.05 1.2)
			(end 1.05 1.2)
			(stroke
				(width 0.2)
				(type solid)
			)
			(layer "F.Fab")
		)
		(fp_line
			(start -0.5 0)
			(end 0.5 0)
			(stroke
				(width 0.1)
				(type solid)
			)
			(layer "F.Fab")
		)
		(fp_line
			(start 0 0.5)
			(end 0 -0.5)
			(stroke
				(width 0.1)
				(type solid)
			)
			(layer "F.Fab")
		)
		(fp_line
			(start 1.05 1.2)
			(end 1.05 -1.2)
			(stroke
				(width 0.2)
				(type solid)
			)
			(layer "F.Fab")
		)
		(fp_text user "${REFERENCE}"
			(at -0.00001 0.09602 0)
			(unlocked yes)
			(layer "F.Fab")
			(effects
				(font
					(face "Arial")
					(size 0.63 0.63)
					(thickness 0.1)
				)
				(justify left bottom)
			)
		)
		(pad "" smd custom
			(at -0.5 -1.1)
			(size 0.000001 0.000001)
			(layers "F.Cu" "F.Mask")
			(solder_mask_margin 0)
			(thermal_bridge_angle 90)
			(options
				(clearance outline)
				(anchor circle)
			)
			(primitives
				(gr_poly
					(pts
						(xy 0 0) (xy 0.15 0) (xy 0.15 0.4) (xy -0.45 0.4) (xy -0.45 0.2) (xy 0 0.2)
					)
					(width 0)
					(fill yes)
				)
			)
		)
		(pad "1" smd circle
			(at -0.45 -0.8)
			(size 0.18 0.18)
			(layers "F.Cu" "F.Mask" "F.Paste")
			(net "DIP_SW_MACSER_SEL")
			(solder_mask_margin 0)
			(solder_paste_margin -1000)
			(thermal_bridge_angle 90)
		)
		(pad "2" smd rect
			(at -0.65 -0.4)
			(size 0.6 0.2)
			(layers "F.Cu" "F.Mask" "F.Paste")
			(net "NetR94_2")
			(solder_mask_margin 0)
			(solder_paste_margin -1000)
		)
		(pad "3" smd rect
			(at -0.65 0)
			(size 0.6 0.2)
			(layers "F.Cu" "F.Mask" "F.Paste")
			(net "GND")
			(solder_mask_margin 0)
			(solder_paste_margin -1000)
		)
		(pad "4" smd rect
			(at -0.65 0.4)
			(size 0.6 0.2)
			(layers "F.Cu" "F.Mask" "F.Paste")
			(net "NetR111_2")
			(solder_mask_margin 0)
			(solder_paste_margin -1000)
		)
		(pad "5" smd rect
			(at -0.65 0.8)
			(size 0.6 0.2)
			(layers "F.Cu" "F.Mask" "F.Paste")
			(net "DIP_SW_MACSER_SEL")
			(solder_mask_margin 0)
			(solder_paste_margin -1000)
		)
		(pad "6" smd rect
			(at 0 0.8)
			(size 0.2 0.6)
			(layers "F.Cu" "F.Mask" "F.Paste")
			(net "GND")
			(solder_mask_margin 0)
			(solder_paste_margin -1000)
		)
		(pad "7" smd rect
			(at 0.65 0.8)
			(size 0.6 0.2)
			(layers "F.Cu" "F.Mask" "F.Paste")
			(net "MAC_RX")
			(solder_mask_margin 0)
			(solder_paste_margin -1000)
		)
		(pad "8" smd rect
			(at 0.65 0.4)
			(size 0.6 0.2)
			(layers "F.Cu" "F.Mask" "F.Paste")
			(net "NetR95_2")
			(solder_mask_margin 0)
			(solder_paste_margin -1000)
		)
		(pad "9" smd rect
			(at 0.65 0)
			(size 0.6 0.2)
			(layers "F.Cu" "F.Mask" "F.Paste")
			(net "+3.3V")
			(solder_mask_margin 0)
			(solder_paste_margin -1000)
		)
		(pad "10" smd rect
			(at 0.65 -0.4)
			(size 0.6 0.2)
			(layers "F.Cu" "F.Mask" "F.Paste")
			(net "NetR76_2")
			(solder_mask_margin 0)
			(solder_paste_margin -1000)
		)
		(pad "11" smd rect
			(at 0.65 -0.8)
			(size 0.6 0.2)
			(layers "F.Cu" "F.Mask" "F.Paste")
			(net "MAC_TX")
			(solder_mask_margin 0)
			(solder_paste_margin -1000)
		)
		(pad "12" smd rect
			(at 0 -0.8)
			(size 0.2 0.6)
			(layers "F.Cu" "F.Mask" "F.Paste")
			(net "GND")
			(solder_mask_margin 0)
			(solder_paste_margin -1000)
		)
	)
	(footprint "SamacSys:155124M173200"
		(layer "F.Cu")
		(at 67.4466 71.6662 90)
		(property "Reference" "D13"
			(at -4.7 -0.231655 90)
			(unlocked yes)
			(layer "F.SilkS")
			(effects
				(font
					(size 0.762 0.762)
					(thickness 0.2286)
				)
				(justify left bottom)
			)
		)
		(property "Value" "155124M173200"
			(at -4.043045 -0.5715 0)
			(unlocked yes)
			(layer "F.SilkS")
			(hide yes)
			(effects
				(font
					(size 0.762 0.762)
					(thickness 0.2286)
				)
				(justify left bottom)
			)
		)
		(sheetname "02-USER_IO_STATUS")
		(sheetfile "02-USER_IO_STATUS.kicad_sch")
		(duplicate_pad_numbers_are_jumpers no)
		(fp_line
			(start -0.8 0.5)
			(end 0.8 0.5)
			(stroke
				(width 0.1)
				(type solid)
			)
			(layer "F.SilkS")
		)
		(fp_arc
			(start -2 -0.0754)
			(mid -1.9746 -0.05)
			(end -2 -0.0246)
			(stroke
				(width 0.381)
				(type solid)
			)
			(layer "F.SilkS")
		)
		(fp_arc
			(start -2 -0.0246)
			(mid -2.0254 -0.05)
			(end -2 -0.0754)
			(stroke
				(width 0.381)
				(type solid)
			)
			(layer "F.SilkS")
		)
		(pad "1" smd rect
			(at -1.4 0 180)
			(size 0.9 0.6)
			(layers "F.Cu" "F.Mask" "F.Paste")
			(net "+3.3V")
		)
		(pad "2" smd rect
			(at -0.45 -0.325 90)
			(size 0.6 0.55)
			(layers "F.Cu" "F.Mask" "F.Paste")
			(net "NetD13_2")
		)
		(pad "3" smd rect
			(at 0.45 -0.325 90)
			(size 0.6 0.55)
			(layers "F.Cu" "F.Mask" "F.Paste")
			(net "NetD13_3")
		)
		(pad "4" smd rect
			(at 1.4 0 180)
			(size 0.9 0.6)
			(layers "F.Cu" "F.Mask" "F.Paste")
			(net "NetD13_4")
		)
	)
	(footprint "Vault:FP-GRM31C-0_2-e0_3_0_8-IPC_C"
		(layer "F.Cu")
		(at 79.9216 59.9162 180)
		(property "Reference" "C11"
			(at 4 -0.493345 0)
			(unlocked yes)
			(layer "F.SilkS")
			(effects
				(font
					(size 0.762 0.762)
					(thickness 0.2286)
				)
				(justify left bottom)
			)
		)
		(property "Value" "4.7uF_50V_1206"
			(at 0.1957 -23.717045 0)
			(unlocked yes)
			(layer "F.SilkS")
			(hide yes)
			(effects
				(font
					(size 0.762 0.762)
					(thickness 0.2286)
				)
				(justify left bottom)
			)
		)
		(sheetname "03-POWER")
		(sheetfile "03-POWER.kicad_sch")
		(duplicate_pad_numbers_are_jumpers no)
		(fp_line
			(start 0.39847 0.9)
			(end -0.39846 0.9)
			(stroke
				(width 0.2)
				(type solid)
			)
			(layer "F.SilkS")
		)
		(fp_line
			(start 0.39847 -0.9)
			(end -0.39846 -0.9)
			(stroke
				(width 0.2)
				(type solid)
			)
			(layer "F.SilkS")
		)
		(fp_line
			(start 1.9531 1)
			(end -1.9531 1)
			(stroke
				(width 0.2)
				(type solid)
			)
			(layer "F.CrtYd")
		)
		(fp_line
			(start 1.9531 -1)
			(end 1.9531 1)
			(stroke
				(width 0.2)
				(type solid)
			)
			(layer "F.CrtYd")
		)
		(fp_line
			(start 1.9531 -1)
			(end -1.9531 -1)
			(stroke
				(width 0.2)
				(type solid)
			)
			(layer "F.CrtYd")
		)
		(fp_line
			(start -1.9531 -1)
			(end -1.9531 1)
			(stroke
				(width 0.2)
				(type solid)
			)
			(layer "F.CrtYd")
		)
		(fp_line
			(start 1.9531 1)
			(end -1.9531 1)
			(stroke
				(width 0.2)
				(type solid)
			)
			(layer "F.Fab")
		)
		(fp_line
			(start 1.9531 -1)
			(end 1.9531 1)
			(stroke
				(width 0.2)
				(type solid)
			)
			(layer "F.Fab")
		)
		(fp_line
			(start 1.9531 -1)
			(end -1.9531 -1)
			(stroke
				(width 0.2)
				(type solid)
			)
			(layer "F.Fab")
		)
		(fp_line
			(start 0.5 0)
			(end -0.5 0)
			(stroke
				(width 0.1)
				(type solid)
			)
			(layer "F.Fab")
		)
		(fp_line
			(start 0 -0.5)
			(end 0 0.5)
			(stroke
				(width 0.1)
				(type solid)
			)
			(layer "F.Fab")
		)
		(fp_line
			(start -1.9531 -1)
			(end -1.9531 1)
			(stroke
				(width 0.2)
				(type solid)
			)
			(layer "F.Fab")
		)
		(fp_text user "${REFERENCE}"
			(at -0.00001 0.09601 180)
			(unlocked yes)
			(layer "F.Fab")
			(effects
				(font
					(face "Arial")
					(size 0.63 0.63)
					(thickness 0.1)
				)
				(justify left bottom)
			)
		)
		(pad "1" smd rect
			(at -1.27578 0 180)
			(size 1.15464 1.7062)
			(layers "F.Cu" "F.Mask" "F.Paste")
			(net "+12V")
			(solder_mask_margin 0)
			(solder_paste_margin 0)
		)
		(pad "2" smd rect
			(at 1.27578 0 180)
			(size 1.15464 1.7062)
			(layers "F.Cu" "F.Mask" "F.Paste")
			(net "GND")
			(solder_mask_margin 0)
			(solder_paste_margin 0)
		)
	)
	(footprint "Vault:FP-1571983-4-MFG"
		(layer "F.Cu")
		(at 227.05584 106.89495 90)
		(property "Reference" "SW1"
			(at 2.328605 4.126931 90)
			(unlocked yes)
			(layer "F.SilkS")
			(effects
				(font
					(size 0.762 0.762)
					(thickness 0.2286)
				)
			)
		)
		(property "Value" "1571983-4"
			(at 3.998655 6.085081 90)
			(unlocked yes)
			(layer "F.SilkS")
			(hide yes)
			(effects
				(font
					(size 0.762 0.762)
					(thickness 0.2286)
				)
			)
		)
		(sheetname "08-DIPSwitches_I2C")
		(sheetfile "08-DIPSwitches_I2C.kicad_sch")
		(duplicate_pad_numbers_are_jumpers no)
		(fp_line
			(start 3.355 -3.225)
			(end 3.355 3.225)
			(stroke
				(width 0.2)
				(type solid)
			)
			(layer "F.SilkS")
		)
		(fp_line
			(start 2.66 -3.225)
			(end 3.355 -3.225)
			(stroke
				(width 0.2)
				(type solid)
			)
			(layer "F.SilkS")
		)
		(fp_line
			(start -3.355 -3.225)
			(end -2.66 -3.225)
			(stroke
				(width 0.2)
				(type solid)
			)
			(layer "F.SilkS")
		)
		(fp_line
			(start -3.355 -3.225)
			(end -3.355 3.225)
			(stroke
				(width 0.2)
				(type solid)
			)
			(layer "F.SilkS")
		)
		(fp_line
			(start 2.66 3.225)
			(end 3.355 3.225)
			(stroke
				(width 0.2)
				(type solid)
			)
			(layer "F.SilkS")
		)
		(fp_line
			(start -3.355 3.225)
			(end -2.66 3.225)
			(stroke
				(width 0.2)
				(type solid)
			)
			(layer "F.SilkS")
		)
		(fp_circle
			(center -3.22125 3.86576)
			(end -3.09625 3.86576)
			(stroke
				(width 0.25)
				(type solid)
			)
			(fill no)
			(layer "F.SilkS")
		)
		(fp_line
			(start 3.455 -4.53)
			(end 3.455 4.53)
			(stroke
				(width 0.2)
				(type solid)
			)
			(layer "F.CrtYd")
		)
		(fp_line
			(start -3.455 -4.53)
			(end 3.455 -4.53)
			(stroke
				(width 0.2)
				(type solid)
			)
			(layer "F.CrtYd")
		)
		(fp_line
			(start -3.455 -4.53)
			(end -3.455 4.53)
			(stroke
				(width 0.2)
				(type solid)
			)
			(layer "F.CrtYd")
		)
		(fp_line
			(start -3.455 4.53)
			(end 3.455 4.53)
			(stroke
				(width 0.2)
				(type solid)
			)
			(layer "F.CrtYd")
		)
		(fp_line
			(start 3.455 -4.53)
			(end 3.455 4.53)
			(stroke
				(width 0.2)
				(type solid)
			)
			(layer "F.Fab")
		)
		(fp_line
			(start -3.455 -4.53)
			(end 3.455 -4.53)
			(stroke
				(width 0.2)
				(type solid)
			)
			(layer "F.Fab")
		)
		(fp_line
			(start -3.455 -4.53)
			(end -3.455 4.53)
			(stroke
				(width 0.2)
				(type solid)
			)
			(layer "F.Fab")
		)
		(fp_line
			(start 0 -0.5)
			(end 0 0.5)
			(stroke
				(width 0.1)
				(type solid)
			)
			(layer "F.Fab")
		)
		(fp_line
			(start -0.5 0)
			(end 0.5 0)
			(stroke
				(width 0.1)
				(type solid)
			)
			(layer "F.Fab")
		)
		(fp_line
			(start -3.455 4.53)
			(end 3.455 4.53)
			(stroke
				(width 0.2)
				(type solid)
			)
			(layer "F.Fab")
		)
		(fp_text user "${REFERENCE}"
			(at -0.00001 0.09602 90)
			(unlocked yes)
			(layer "F.Fab")
			(effects
				(font
					(face "Arial")
					(size 0.63 0.63)
					(thickness 0.1)
				)
				(justify left bottom)
			)
		)
		(pad "1" smd rect
			(at -1.905 3.795 90)
			(size 0.76 1.27)
			(layers "F.Cu" "F.Mask" "F.Paste")
			(net "GND")
			(solder_mask_margin 0)
			(solder_paste_margin 0)
		)
		(pad "2" smd rect
			(at -0.635 3.795 90)
			(size 0.76 1.27)
			(layers "F.Cu" "F.Mask" "F.Paste")
			(net "GND")
			(solder_mask_margin 0)
			(solder_paste_margin 0)
		)
		(pad "3" smd rect
			(at 0.635 3.795 90)
			(size 0.76 1.27)
			(layers "F.Cu" "F.Mask" "F.Paste")
			(net "GND")
			(solder_mask_margin 0)
			(solder_paste_margin 0)
		)
		(pad "4" smd rect
			(at 1.905 3.795 90)
			(size 0.76 1.27)
			(layers "F.Cu" "F.Mask" "F.Paste")
			(net "GND")
			(solder_mask_margin 0)
			(solder_paste_margin 0)
		)
		(pad "5" smd rect
			(at 1.905 -3.795 90)
			(size 0.76 1.27)
			(layers "F.Cu" "F.Mask" "F.Paste")
			(solder_mask_margin 0)
			(solder_paste_margin 0)
		)
		(pad "6" smd rect
			(at 0.635 -3.795 90)
			(size 0.76 1.27)
			(layers "F.Cu" "F.Mask" "F.Paste")
			(net "DIP_SW_MACSER_SEL")
			(solder_mask_margin 0)
			(solder_paste_margin 0)
		)
		(pad "7" smd rect
			(at -0.635 -3.795 90)
			(size 0.76 1.27)
			(layers "F.Cu" "F.Mask" "F.Paste")
			(net "DIP_SW_PPS_SEL")
			(solder_mask_margin 0)
			(solder_paste_margin 0)
		)
		(pad "8" smd rect
			(at -1.905 -3.795 90)
			(size 0.76 1.27)
			(layers "F.Cu" "F.Mask" "F.Paste")
			(net "DIP_SW_UART_SEL")
			(solder_mask_margin 0)
			(solder_paste_margin 0)
		)
	)
	(footprint "Vault:FP-LTST-C191KGKT-MFG"
		(layer "F.Cu")
		(at 79.4216 52.1162)
		(property "Reference" "D9"
			(at -4.171405 -0.373079 0)
			(unlocked yes)
			(layer "F.SilkS")
			(effects
				(font
					(size 0.762 0.762)
					(thickness 0.2286)
				)
			)
		)
		(property "Value" "LTST-C191KGKT"
			(at 1.2818 2.452871 0)
			(unlocked yes)
			(layer "F.SilkS")
			(hide yes)
			(effects
				(font
					(size 0.762 0.762)
					(thickness 0.2286)
				)
			)
		)
		(sheetname "02-USER_IO_STATUS")
		(sheetfile "02-USER_IO_STATUS.kicad_sch")
		(duplicate_pad_numbers_are_jumpers no)
		(fp_line
			(start -0.85 -0.775)
			(end 0.85 -0.775)
			(stroke
				(width 0.2)
				(type solid)
			)
			(layer "F.SilkS")
		)
		(fp_line
			(start -0.85 0.775)
			(end 0.85 0.775)
			(stroke
				(width 0.2)
				(type solid)
			)
			(layer "F.SilkS")
		)
		(fp_circle
			(center -1.7 0)
			(end -1.7 -0.125)
			(stroke
				(width 0.25)
				(type solid)
			)
			(fill no)
			(layer "F.SilkS")
		)
		(fp_line
			(start -1.25 -0.55)
			(end 1.25 -0.55)
			(stroke
				(width 0.2)
				(type solid)
			)
			(layer "F.CrtYd")
		)
		(fp_line
			(start -1.25 0.55)
			(end -1.25 -0.55)
			(stroke
				(width 0.2)
				(type solid)
			)
			(layer "F.CrtYd")
		)
		(fp_line
			(start -1.25 0.55)
			(end 1.25 0.55)
			(stroke
				(width 0.2)
				(type solid)
			)
			(layer "F.CrtYd")
		)
		(fp_line
			(start 1.25 0.55)
			(end 1.25 -0.55)
			(stroke
				(width 0.2)
				(type solid)
			)
			(layer "F.CrtYd")
		)
		(fp_line
			(start -1.25 -0.55)
			(end 1.25 -0.55)
			(stroke
				(width 0.2)
				(type solid)
			)
			(layer "F.Fab")
		)
		(fp_line
			(start -1.25 0.55)
			(end -1.25 -0.55)
			(stroke
				(width 0.2)
				(type solid)
			)
			(layer "F.Fab")
		)
		(fp_line
			(start -1.25 0.55)
			(end 1.25 0.55)
			(stroke
				(width 0.2)
				(type solid)
			)
			(layer "F.Fab")
		)
		(fp_line
			(start -0.5 0)
			(end 0.5 0)
			(stroke
				(width 0.1)
				(type solid)
			)
			(layer "F.Fab")
		)
		(fp_line
			(start 0 0.5)
			(end 0 -0.5)
			(stroke
				(width 0.1)
				(type solid)
			)
			(layer "F.Fab")
		)
		(fp_line
			(start 1.25 0.55)
			(end 1.25 -0.55)
			(stroke
				(width 0.2)
				(type solid)
			)
			(layer "F.Fab")
		)
		(fp_text user "${REFERENCE}"
			(at 0 0.28425 360)
			(unlocked yes)
			(layer "F.Fab")
			(effects
				(font
					(face "Arial")
					(size 0.63 0.63)
					(thickness 0.1)
				)
				(justify left bottom)
			)
		)
		(pad "1" smd rect
			(at -0.75 0)
			(size 0.8 0.8)
			(layers "F.Cu" "F.Mask" "F.Paste")
			(net "NetD9_1")
			(solder_mask_margin 0)
			(solder_paste_margin 0)
		)
		(pad "2" smd rect
			(at 0.75 0)
			(size 0.8 0.8)
			(layers "F.Cu" "F.Mask" "F.Paste")
			(net "+3.3V")
			(solder_mask_margin 0)
			(solder_paste_margin 0)
		)
	)
)
